(kicad_pcb
	(version 20260206)
	(generator "pcbnew")
	(generator_version "10.0")
	(general
		(thickness 1.6)
		(legacy_teardrops no)
	)
	(paper "A4")
	(title_block
		(title "04192023_DAF0TMB3IC0_F0TG_MB_C_brd_V02_OCP.brd")
		(comment 1 "Grand Teton / footprints 1670-1676 of 8354")
	)
	(layers
		(0 "F.Cu" signal "TOP")
		(4 "In1.Cu" signal "GND")
		(6 "In2.Cu" signal "IN1")
		(8 "In3.Cu" signal "GND1")
		(10 "In4.Cu" signal "IN2")
		(12 "In5.Cu" signal "GND2")
		(14 "In6.Cu" signal "IN3")
		(16 "In7.Cu" signal "GND3")
		(18 "In8.Cu" signal "VCC")
		(20 "In9.Cu" signal "VCC1")
		(22 "In10.Cu" signal "GND4")
		(24 "In11.Cu" signal "IN4")
		(26 "In12.Cu" signal "GND5")
		(28 "In13.Cu" signal "IN5")
		(30 "In14.Cu" signal "GND6")
		(32 "In15.Cu" signal "IN6")
		(34 "In16.Cu" signal "GND7")
		(2 "B.Cu" signal "BOTTOM")
		(9 "F.Adhes" user "F.Adhesive")
		(11 "B.Adhes" user "B.Adhesive")
		(13 "F.Paste" user "Package Geometry/Pastemask Top")
		(15 "B.Paste" user "Package Geometry/Pastemask Bottom")
		(5 "F.SilkS" user "Ref Des/Silkscreen Top")
		(7 "B.SilkS" user "Ref Des/Silkscreen Bottom")
		(1 "F.Mask" user "Board Geometry/Soldermask Top")
		(3 "B.Mask" user "Board Geometry/Soldermask Bottom")
		(17 "Dwgs.User" user "User.Drawings")
		(19 "Cmts.User" user "User.Comments")
		(21 "Eco1.User" user "User.Eco1")
		(23 "Eco2.User" user "User.Eco2")
		(25 "Edge.Cuts" user "Board Geometry/Outline")
		(27 "Margin" user)
		(31 "F.CrtYd" user "Package Geometry/Place Bound Top")
		(29 "B.CrtYd" user "Package Geometry/Place Bound Bottom")
		(35 "F.Fab" user "Ref Des/Assembly Top")
		(33 "B.Fab" user "Ref Des/Assembly Bottom")
	)
	(footprint ""
		(layer "F.Cu")
		(at 359.190036 -393.47648 180)
		(property "Reference" "L28"
			(at 0 0 180)
			(layer "F.SilkS")
			(hide yes)
			(effects
				(font
					(size 1.27 1.27)
				)
			)
		)
		(property "Value" ""
			(at 0 0 180)
			(layer "F.Fab")
			(effects
				(font
					(size 1.27 1.27)
				)
			)
		)
		(duplicate_pad_numbers_are_jumpers no)
		(fp_line
			(start 0.762 0.381)
			(end -0.762 0.381)
			(stroke
				(width 0.1524)
				(type default)
			)
			(layer "F.SilkS")
		)
		(fp_line
			(start 0.762 -0.381)
			(end 0.762 0.381)
			(stroke
				(width 0.1524)
				(type default)
			)
			(layer "F.SilkS")
		)
		(fp_line
			(start -0.762 0.381)
			(end -0.762 -0.381)
			(stroke
				(width 0.1524)
				(type default)
			)
			(layer "F.SilkS")
		)
		(fp_line
			(start -0.762 -0.381)
			(end 0.762 -0.381)
			(stroke
				(width 0.1524)
				(type default)
			)
			(layer "F.SilkS")
		)
		(fp_line
			(start 0.680466 0.306324)
			(end 0.118364 0.306324)
			(stroke
				(width 0.1)
				(type default)
			)
			(layer "F.Fab")
		)
		(fp_line
			(start 0.680466 -0.306324)
			(end 0.680466 0.306324)
			(stroke
				(width 0.1)
				(type default)
			)
			(layer "F.Fab")
		)
		(fp_line
			(start 0.118872 -0.2794)
			(end 0.118872 -0.306324)
			(stroke
				(width 0.1)
				(type default)
			)
			(layer "F.Fab")
		)
		(fp_line
			(start 0.118872 -0.306324)
			(end 0.680466 -0.306324)
			(stroke
				(width 0.1)
				(type default)
			)
			(layer "F.Fab")
		)
		(fp_line
			(start 0.118364 0.306324)
			(end 0.118364 0.2794)
			(stroke
				(width 0.1)
				(type default)
			)
			(layer "F.Fab")
		)
		(fp_line
			(start 0.118364 0.2794)
			(end -0.119634 0.2794)
			(stroke
				(width 0.1)
				(type default)
			)
			(layer "F.Fab")
		)
		(fp_line
			(start -0.118364 -0.2794)
			(end 0.118872 -0.2794)
			(stroke
				(width 0.1)
				(type default)
			)
			(layer "F.Fab")
		)
		(fp_line
			(start -0.118364 -0.307086)
			(end -0.118364 -0.2794)
			(stroke
				(width 0.1)
				(type default)
			)
			(layer "F.Fab")
		)
		(fp_line
			(start -0.119634 0.30607)
			(end -0.681736 0.30607)
			(stroke
				(width 0.1)
				(type default)
			)
			(layer "F.Fab")
		)
		(fp_line
			(start -0.119634 0.2794)
			(end -0.119634 0.30607)
			(stroke
				(width 0.1)
				(type default)
			)
			(layer "F.Fab")
		)
		(fp_line
			(start -0.681736 0.30607)
			(end -0.681736 -0.307086)
			(stroke
				(width 0.1)
				(type default)
			)
			(layer "F.Fab")
		)
		(fp_line
			(start -0.681736 -0.307086)
			(end -0.118364 -0.307086)
			(stroke
				(width 0.1)
				(type default)
			)
			(layer "F.Fab")
		)
		(pad "1" smd rect
			(at -0.40005 0)
			(size 0.4572 0.508)
			(layers "F.Cu" "F.Mask" "F.Paste")
			(net "P1V8_CPU0_RT_1D")
		)
		(pad "2" smd rect
			(at 0.40005 0)
			(size 0.4572 0.508)
			(layers "F.Cu" "F.Mask" "F.Paste")
			(net "P1V8_CPU0_RT1_1A_1D")
		)
	)
	(footprint ""
		(layer "F.Cu")
		(at 117.895624 -262.205216 180)
		(property "Reference" "C2487"
			(at 0 0 180)
			(layer "F.SilkS")
			(hide yes)
			(effects
				(font
					(size 1.27 1.27)
				)
			)
		)
		(property "Value" ""
			(at 0 0 180)
			(layer "F.Fab")
			(effects
				(font
					(size 1.27 1.27)
				)
			)
		)
		(duplicate_pad_numbers_are_jumpers no)
		(fp_line
			(start 0.7874 0.4064)
			(end -0.7874 0.4064)
			(stroke
				(width 0.1524)
				(type default)
			)
			(layer "F.SilkS")
		)
		(fp_line
			(start 0.7874 -0.4064)
			(end 0.7874 0.4064)
			(stroke
				(width 0.1524)
				(type default)
			)
			(layer "F.SilkS")
		)
		(fp_line
			(start -0.7874 0.4064)
			(end -0.7874 -0.4064)
			(stroke
				(width 0.1524)
				(type default)
			)
			(layer "F.SilkS")
		)
		(fp_line
			(start -0.7874 -0.4064)
			(end 0.7874 -0.4064)
			(stroke
				(width 0.1524)
				(type default)
			)
			(layer "F.SilkS")
		)
		(fp_line
			(start 0.67945 0.3048)
			(end 0.120396 0.3048)
			(stroke
				(width 0.1)
				(type default)
			)
			(layer "F.Fab")
		)
		(fp_line
			(start 0.67945 -0.3048)
			(end 0.67945 0.3048)
			(stroke
				(width 0.1)
				(type default)
			)
			(layer "F.Fab")
		)
		(fp_line
			(start 0.12065 -0.2794)
			(end 0.12065 -0.3048)
			(stroke
				(width 0.1)
				(type default)
			)
			(layer "F.Fab")
		)
		(fp_line
			(start 0.12065 -0.3048)
			(end 0.67945 -0.3048)
			(stroke
				(width 0.1)
				(type default)
			)
			(layer "F.Fab")
		)
		(fp_line
			(start 0.120396 0.3048)
			(end 0.120396 0.2794)
			(stroke
				(width 0.1)
				(type default)
			)
			(layer "F.Fab")
		)
		(fp_line
			(start 0.120396 0.2794)
			(end -0.12065 0.2794)
			(stroke
				(width 0.1)
				(type default)
			)
			(layer "F.Fab")
		)
		(fp_line
			(start -0.12065 0.3048)
			(end -0.67945 0.3048)
			(stroke
				(width 0.1)
				(type default)
			)
			(layer "F.Fab")
		)
		(fp_line
			(start -0.12065 0.2794)
			(end -0.12065 0.3048)
			(stroke
				(width 0.1)
				(type default)
			)
			(layer "F.Fab")
		)
		(fp_line
			(start -0.12065 -0.2794)
			(end 0.12065 -0.2794)
			(stroke
				(width 0.1)
				(type default)
			)
			(layer "F.Fab")
		)
		(fp_line
			(start -0.12065 -0.305054)
			(end -0.12065 -0.2794)
			(stroke
				(width 0.1)
				(type default)
			)
			(layer "F.Fab")
		)
		(fp_line
			(start -0.67945 0.3048)
			(end -0.67945 -0.305054)
			(stroke
				(width 0.1)
				(type default)
			)
			(layer "F.Fab")
		)
		(fp_line
			(start -0.67945 -0.305054)
			(end -0.12065 -0.305054)
			(stroke
				(width 0.1)
				(type default)
			)
			(layer "F.Fab")
		)
		(pad "1" smd circle
			(at -0.40005 0 180)
			(size 0 0)
			(layers "F.Cu" "F.Mask" "F.Paste")
			(net "PVDD11_S3_P1")
		)
		(pad "2" smd circle
			(at 0.40005 0 180)
			(size 0 0)
			(layers "F.Cu" "F.Mask" "F.Paste")
			(net "GND")
		)
	)
	(footprint ""
		(layer "F.Cu")
		(at 16.051784 -394.428726)
		(property "Reference" "PR6622"
			(at 0 0 0)
			(layer "F.SilkS")
			(hide yes)
			(effects
				(font
					(size 1.27 1.27)
				)
			)
		)
		(property "Value" ""
			(at 0 0 0)
			(layer "F.Fab")
			(effects
				(font
					(size 1.27 1.27)
				)
			)
		)
		(duplicate_pad_numbers_are_jumpers no)
		(fp_line
			(start -0.7874 -0.4064)
			(end 0.7874 -0.4064)
			(stroke
				(width 0.1524)
				(type default)
			)
			(layer "F.SilkS")
		)
		(fp_line
			(start -0.7874 0.4064)
			(end -0.7874 -0.4064)
			(stroke
				(width 0.1524)
				(type default)
			)
			(layer "F.SilkS")
		)
		(fp_line
			(start 0.7874 -0.4064)
			(end 0.7874 0.4064)
			(stroke
				(width 0.1524)
				(type default)
			)
			(layer "F.SilkS")
		)
		(fp_line
			(start 0.7874 0.4064)
			(end -0.7874 0.4064)
			(stroke
				(width 0.1524)
				(type default)
			)
			(layer "F.SilkS")
		)
		(fp_line
			(start -0.67945 -0.305054)
			(end -0.12065 -0.305054)
			(stroke
				(width 0.1)
				(type default)
			)
			(layer "F.Fab")
		)
		(fp_line
			(start -0.67945 0.3048)
			(end -0.67945 -0.305054)
			(stroke
				(width 0.1)
				(type default)
			)
			(layer "F.Fab")
		)
		(fp_line
			(start -0.12065 -0.305054)
			(end -0.12065 -0.2794)
			(stroke
				(width 0.1)
				(type default)
			)
			(layer "F.Fab")
		)
		(fp_line
			(start -0.12065 -0.2794)
			(end 0.12065 -0.2794)
			(stroke
				(width 0.1)
				(type default)
			)
			(layer "F.Fab")
		)
		(fp_line
			(start -0.12065 0.2794)
			(end -0.12065 0.3048)
			(stroke
				(width 0.1)
				(type default)
			)
			(layer "F.Fab")
		)
		(fp_line
			(start -0.12065 0.3048)
			(end -0.67945 0.3048)
			(stroke
				(width 0.1)
				(type default)
			)
			(layer "F.Fab")
		)
		(fp_line
			(start 0.120396 0.2794)
			(end -0.12065 0.2794)
			(stroke
				(width 0.1)
				(type default)
			)
			(layer "F.Fab")
		)
		(fp_line
			(start 0.120396 0.3048)
			(end 0.120396 0.2794)
			(stroke
				(width 0.1)
				(type default)
			)
			(layer "F.Fab")
		)
		(fp_line
			(start 0.12065 -0.3048)
			(end 0.67945 -0.3048)
			(stroke
				(width 0.1)
				(type default)
			)
			(layer "F.Fab")
		)
		(fp_line
			(start 0.12065 -0.2794)
			(end 0.12065 -0.3048)
			(stroke
				(width 0.1)
				(type default)
			)
			(layer "F.Fab")
		)
		(fp_line
			(start 0.67945 -0.3048)
			(end 0.67945 0.3048)
			(stroke
				(width 0.1)
				(type default)
			)
			(layer "F.Fab")
		)
		(fp_line
			(start 0.67945 0.3048)
			(end 0.120396 0.3048)
			(stroke
				(width 0.1)
				(type default)
			)
			(layer "F.Fab")
		)
		(pad "1" smd circle
			(at -0.40005 0)
			(size 0 0)
			(layers "F.Cu" "F.Mask" "F.Paste")
			(net "P0V9_RETIMER_CPU1_LSET1")
		)
		(pad "2" smd circle
			(at 0.40005 0)
			(size 0 0)
			(layers "F.Cu" "F.Mask" "F.Paste")
			(net "GND")
		)
	)
	(footprint ""
		(layer "F.Cu")
		(at 434.448204 -103.927402 -90)
		(property "Reference" "PC2089"
			(at 0 0 270)
			(layer "F.SilkS")
			(hide yes)
			(effects
				(font
					(size 1.27 1.27)
				)
			)
		)
		(property "Value" ""
			(at 0 0 270)
			(layer "F.Fab")
			(effects
				(font
					(size 1.27 1.27)
				)
			)
		)
		(duplicate_pad_numbers_are_jumpers no)
		(fp_line
			(start -0.7874 0.4064)
			(end -0.7874 -0.4064)
			(stroke
				(width 0.1524)
				(type default)
			)
			(layer "F.SilkS")
		)
		(fp_line
			(start 0.7874 0.4064)
			(end -0.7874 0.4064)
			(stroke
				(width 0.1524)
				(type default)
			)
			(layer "F.SilkS")
		)
		(fp_line
			(start -0.7874 -0.4064)
			(end 0.7874 -0.4064)
			(stroke
				(width 0.1524)
				(type default)
			)
			(layer "F.SilkS")
		)
		(fp_line
			(start 0.7874 -0.4064)
			(end 0.7874 0.4064)
			(stroke
				(width 0.1524)
				(type default)
			)
			(layer "F.SilkS")
		)
		(fp_line
			(start -0.67945 0.3048)
			(end -0.67945 -0.305054)
			(stroke
				(width 0.1)
				(type default)
			)
			(layer "F.Fab")
		)
		(fp_line
			(start -0.12065 0.3048)
			(end -0.67945 0.3048)
			(stroke
				(width 0.1)
				(type default)
			)
			(layer "F.Fab")
		)
		(fp_line
			(start 0.120396 0.3048)
			(end 0.120396 0.2794)
			(stroke
				(width 0.1)
				(type default)
			)
			(layer "F.Fab")
		)
		(fp_line
			(start 0.67945 0.3048)
			(end 0.120396 0.3048)
			(stroke
				(width 0.1)
				(type default)
			)
			(layer "F.Fab")
		)
		(fp_line
			(start -0.12065 0.2794)
			(end -0.12065 0.3048)
			(stroke
				(width 0.1)
				(type default)
			)
			(layer "F.Fab")
		)
		(fp_line
			(start 0.120396 0.2794)
			(end -0.12065 0.2794)
			(stroke
				(width 0.1)
				(type default)
			)
			(layer "F.Fab")
		)
		(fp_line
			(start -0.12065 -0.2794)
			(end 0.12065 -0.2794)
			(stroke
				(width 0.1)
				(type default)
			)
			(layer "F.Fab")
		)
		(fp_line
			(start 0.12065 -0.2794)
			(end 0.12065 -0.3048)
			(stroke
				(width 0.1)
				(type default)
			)
			(layer "F.Fab")
		)
		(fp_line
			(start 0.12065 -0.3048)
			(end 0.67945 -0.3048)
			(stroke
				(width 0.1)
				(type default)
			)
			(layer "F.Fab")
		)
		(fp_line
			(start 0.67945 -0.3048)
			(end 0.67945 0.3048)
			(stroke
				(width 0.1)
				(type default)
			)
			(layer "F.Fab")
		)
		(fp_line
			(start -0.67945 -0.305054)
			(end -0.12065 -0.305054)
			(stroke
				(width 0.1)
				(type default)
			)
			(layer "F.Fab")
		)
		(fp_line
			(start -0.12065 -0.305054)
			(end -0.12065 -0.2794)
			(stroke
				(width 0.1)
				(type default)
			)
			(layer "F.Fab")
		)
		(pad "1" smd circle
			(at -0.40005 0 270)
			(size 0 0)
			(layers "F.Cu" "F.Mask" "F.Paste")
			(net "P3V3_OCP_GATE_PU202_1")
		)
		(pad "2" smd circle
			(at 0.40005 0 270)
			(size 0 0)
			(layers "F.Cu" "F.Mask" "F.Paste")
			(net "GND")
		)
	)
	(footprint ""
		(layer "F.Cu")
		(at 353.10445 -430.590452 180)
		(property "Reference" "R4560"
			(at 0 0 180)
			(layer "F.SilkS")
			(hide yes)
			(effects
				(font
					(size 1.27 1.27)
				)
			)
		)
		(property "Value" ""
			(at 0 0 180)
			(layer "F.Fab")
			(effects
				(font
					(size 1.27 1.27)
				)
			)
		)
		(duplicate_pad_numbers_are_jumpers no)
		(fp_line
			(start 0.7874 0.4064)
			(end -0.7874 0.4064)
			(stroke
				(width 0.1524)
				(type default)
			)
			(layer "F.SilkS")
		)
		(fp_line
			(start 0.7874 -0.4064)
			(end 0.7874 0.4064)
			(stroke
				(width 0.1524)
				(type default)
			)
			(layer "F.SilkS")
		)
		(fp_line
			(start -0.7874 0.4064)
			(end -0.7874 -0.4064)
			(stroke
				(width 0.1524)
				(type default)
			)
			(layer "F.SilkS")
		)
		(fp_line
			(start -0.7874 -0.4064)
			(end 0.7874 -0.4064)
			(stroke
				(width 0.1524)
				(type default)
			)
			(layer "F.SilkS")
		)
		(fp_line
			(start 0.67945 0.3048)
			(end 0.120396 0.3048)
			(stroke
				(width 0.1)
				(type default)
			)
			(layer "F.Fab")
		)
		(fp_line
			(start 0.67945 -0.3048)
			(end 0.67945 0.3048)
			(stroke
				(width 0.1)
				(type default)
			)
			(layer "F.Fab")
		)
		(fp_line
			(start 0.12065 -0.2794)
			(end 0.12065 -0.3048)
			(stroke
				(width 0.1)
				(type default)
			)
			(layer "F.Fab")
		)
		(fp_line
			(start 0.12065 -0.3048)
			(end 0.67945 -0.3048)
			(stroke
				(width 0.1)
				(type default)
			)
			(layer "F.Fab")
		)
		(fp_line
			(start 0.120396 0.3048)
			(end 0.120396 0.2794)
			(stroke
				(width 0.1)
				(type default)
			)
			(layer "F.Fab")
		)
		(fp_line
			(start 0.120396 0.2794)
			(end -0.12065 0.2794)
			(stroke
				(width 0.1)
				(type default)
			)
			(layer "F.Fab")
		)
		(fp_line
			(start -0.12065 0.3048)
			(end -0.67945 0.3048)
			(stroke
				(width 0.1)
				(type default)
			)
			(layer "F.Fab")
		)
		(fp_line
			(start -0.12065 0.2794)
			(end -0.12065 0.3048)
			(stroke
				(width 0.1)
				(type default)
			)
			(layer "F.Fab")
		)
		(fp_line
			(start -0.12065 -0.2794)
			(end 0.12065 -0.2794)
			(stroke
				(width 0.1)
				(type default)
			)
			(layer "F.Fab")
		)
		(fp_line
			(start -0.12065 -0.305054)
			(end -0.12065 -0.2794)
			(stroke
				(width 0.1)
				(type default)
			)
			(layer "F.Fab")
		)
		(fp_line
			(start -0.67945 0.3048)
			(end -0.67945 -0.305054)
			(stroke
				(width 0.1)
				(type default)
			)
			(layer "F.Fab")
		)
		(fp_line
			(start -0.67945 -0.305054)
			(end -0.12065 -0.305054)
			(stroke
				(width 0.1)
				(type default)
			)
			(layer "F.Fab")
		)
		(pad "1" smd circle
			(at -0.40005 0 180)
			(size 0 0)
			(layers "F.Cu" "F.Mask" "F.Paste")
			(net "P3V3_AUX")
		)
		(pad "2" smd circle
			(at 0.40005 0 180)
			(size 0 0)
			(layers "F.Cu" "F.Mask" "F.Paste")
			(net "SWB_HSC_PWRGD_N")
		)
	)
	(footprint ""
		(layer "F.Cu")
		(at 188.18733 -133.573774 90)
		(property "Reference" "R1553"
			(at 0 0 90)
			(layer "F.SilkS")
			(hide yes)
			(effects
				(font
					(size 1.27 1.27)
				)
			)
		)
		(property "Value" ""
			(at 0 0 90)
			(layer "F.Fab")
			(effects
				(font
					(size 1.27 1.27)
				)
			)
		)
		(duplicate_pad_numbers_are_jumpers no)
		(fp_line
			(start 0.7874 -0.4064)
			(end 0.7874 0.4064)
			(stroke
				(width 0.1524)
				(type default)
			)
			(layer "F.SilkS")
		)
		(fp_line
			(start -0.7874 -0.4064)
			(end 0.7874 -0.4064)
			(stroke
				(width 0.1524)
				(type default)
			)
			(layer "F.SilkS")
		)
		(fp_line
			(start 0.7874 0.4064)
			(end -0.7874 0.4064)
			(stroke
				(width 0.1524)
				(type default)
			)
			(layer "F.SilkS")
		)
		(fp_line
			(start -0.7874 0.4064)
			(end -0.7874 -0.4064)
			(stroke
				(width 0.1524)
				(type default)
			)
			(layer "F.SilkS")
		)
		(fp_line
			(start -0.12065 -0.305054)
			(end -0.12065 -0.2794)
			(stroke
				(width 0.1)
				(type default)
			)
			(layer "F.Fab")
		)
		(fp_line
			(start -0.67945 -0.305054)
			(end -0.12065 -0.305054)
			(stroke
				(width 0.1)
				(type default)
			)
			(layer "F.Fab")
		)
		(fp_line
			(start 0.67945 -0.3048)
			(end 0.67945 0.3048)
			(stroke
				(width 0.1)
				(type default)
			)
			(layer "F.Fab")
		)
		(fp_line
			(start 0.12065 -0.3048)
			(end 0.67945 -0.3048)
			(stroke
				(width 0.1)
				(type default)
			)
			(layer "F.Fab")
		)
		(fp_line
			(start 0.12065 -0.2794)
			(end 0.12065 -0.3048)
			(stroke
				(width 0.1)
				(type default)
			)
			(layer "F.Fab")
		)
		(fp_line
			(start -0.12065 -0.2794)
			(end 0.12065 -0.2794)
			(stroke
				(width 0.1)
				(type default)
			)
			(layer "F.Fab")
		)
		(fp_line
			(start 0.120396 0.2794)
			(end -0.12065 0.2794)
			(stroke
				(width 0.1)
				(type default)
			)
			(layer "F.Fab")
		)
		(fp_line
			(start -0.12065 0.2794)
			(end -0.12065 0.3048)
			(stroke
				(width 0.1)
				(type default)
			)
			(layer "F.Fab")
		)
		(fp_line
			(start 0.67945 0.3048)
			(end 0.120396 0.3048)
			(stroke
				(width 0.1)
				(type default)
			)
			(layer "F.Fab")
		)
		(fp_line
			(start 0.120396 0.3048)
			(end 0.120396 0.2794)
			(stroke
				(width 0.1)
				(type default)
			)
			(layer "F.Fab")
		)
		(fp_line
			(start -0.12065 0.3048)
			(end -0.67945 0.3048)
			(stroke
				(width 0.1)
				(type default)
			)
			(layer "F.Fab")
		)
		(fp_line
			(start -0.67945 0.3048)
			(end -0.67945 -0.305054)
			(stroke
				(width 0.1)
				(type default)
			)
			(layer "F.Fab")
		)
		(pad "1" smd circle
			(at -0.40005 0 90)
			(size 0 0)
			(layers "F.Cu" "F.Mask" "F.Paste")
			(net "ESPI_CPU0_CS1_R_N")
		)
		(pad "2" smd circle
			(at 0.40005 0 90)
			(size 0 0)
			(layers "F.Cu" "F.Mask" "F.Paste")
			(net "ESPI_CPU0_CS1_N")
		)
	)
	(footprint ""
		(layer "F.Cu")
		(at 96.0628 -418.846 180)
		(property "Reference" "R1455"
			(at 0 0 180)
			(layer "F.SilkS")
			(hide yes)
			(effects
				(font
					(size 1.27 1.27)
				)
			)
		)
		(property "Value" ""
			(at 0 0 180)
			(layer "F.Fab")
			(effects
				(font
					(size 1.27 1.27)
				)
			)
		)
		(duplicate_pad_numbers_are_jumpers no)
		(fp_line
			(start 0.32512 0.175006)
			(end -0.32512 0.175006)
			(stroke
				(width 0.1)
				(type default)
			)
			(layer "F.Fab")
		)
		(fp_line
			(start 0.32512 -0.175006)
			(end 0.32512 0.175006)
			(stroke
				(width 0.1)
				(type default)
			)
			(layer "F.Fab")
		)
		(fp_line
			(start -0.32512 0.175006)
			(end -0.32512 -0.175006)
			(stroke
				(width 0.1)
				(type default)
			)
			(layer "F.Fab")
		)
		(fp_line
			(start -0.32512 -0.175006)
			(end 0.32512 -0.175006)
			(stroke
				(width 0.1)
				(type default)
			)
			(layer "F.Fab")
		)
		(pad "1" smd rect
			(at -0.2667 0 180)
			(size 0.3048 0.381)
			(layers "F.Cu" "F.Mask" "F.Paste")
			(net "P1V8_CPU1_RT_1D")
		)
		(pad "2" smd rect
			(at 0.2667 0)
			(size 0.3048 0.381)
			(layers "F.Cu" "F.Mask" "F.Paste")
			(net "JTAG_TMS_RT_CPU1_P1")
		)
	)
)
